# T6G (Grand Teton) — schematic netlist excerpt (pin names and nets, part order shuffled) for the footprints in the layout excerpt that follows; sources: Cadence DE-HDL packaged netlist, KiCad conversion of 04192023_DAF0TMB3IC0_F0TG_MB_C_brd_V02_OCP.brd

C583  Q_CAP  0.1UF 10V 10% X7S  pkg C0201  page 279 : A = P0V9_CPU0_RT0_2A ; B = GND
R1238  Q_RES  18K 1% CHIP  pkg 0402LF  page 258 : A = P5V_AUX ; B = P5V_AUX_ADC
C2517  Q_CAP  22UF 4V 20% X6S  pkg C0402  page 71 : A = PVDD18_S5_P0 ; B = GND

(kicad_pcb
	(version 20260206)
	(generator "pcbnew")
	(generator_version "10.0")
	(general
		(thickness 1.6)
		(legacy_teardrops no)
	)
	(paper "A4")
	(title_block
		(title "04192023_DAF0TMB3IC0_F0TG_MB_C_brd_V02_OCP.brd")
		(comment 1 "Grand Teton / footprints 7174-7176 of 8354")
	)
	(layers
		(0 "F.Cu" signal "TOP")
		(4 "In1.Cu" signal "GND")
		(6 "In2.Cu" signal "IN1")
		(8 "In3.Cu" signal "GND1")
		(10 "In4.Cu" signal "IN2")
		(12 "In5.Cu" signal "GND2")
		(14 "In6.Cu" signal "IN3")
		(16 "In7.Cu" signal "GND3")
		(18 "In8.Cu" signal "VCC")
		(20 "In9.Cu" signal "VCC1")
		(22 "In10.Cu" signal "GND4")
		(24 "In11.Cu" signal "IN4")
		(26 "In12.Cu" signal "GND5")
		(28 "In13.Cu" signal "IN5")
		(30 "In14.Cu" signal "GND6")
		(32 "In15.Cu" signal "IN6")
		(34 "In16.Cu" signal "GND7")
		(2 "B.Cu" signal "BOTTOM")
		(9 "F.Adhes" user "F.Adhesive")
		(11 "B.Adhes" user "B.Adhesive")
		(13 "F.Paste" user "Package Geometry/Pastemask Top")
		(15 "B.Paste" user "Package Geometry/Pastemask Bottom")
		(5 "F.SilkS" user "Ref Des/Silkscreen Top")
		(7 "B.SilkS" user "Ref Des/Silkscreen Bottom")
		(1 "F.Mask" user "Board Geometry/Soldermask Top")
		(3 "B.Mask" user "Board Geometry/Soldermask Bottom")
		(17 "Dwgs.User" user "User.Drawings")
		(19 "Cmts.User" user "User.Comments")
		(21 "Eco1.User" user "User.Eco1")
		(23 "Eco2.User" user "User.Eco2")
		(25 "Edge.Cuts" user "Board Geometry/Outline")
		(27 "Margin" user)
		(31 "F.CrtYd" user "Package Geometry/Place Bound Top")
		(29 "B.CrtYd" user "Package Geometry/Place Bound Bottom")
		(35 "F.Fab" user "Ref Des/Assembly Top")
		(33 "B.Fab" user "Ref Des/Assembly Bottom")
	)
	(footprint ""
		(layer "B.Cu")
		(at 237.905544 -321.471544)
		(property "Reference" "R1238"
			(at 0 0 0)
			(layer "B.SilkS")
			(hide yes)
			(effects
				(font
					(size 1.27 1.27)
				)
				(justify mirror)
			)
		)
		(property "Value" ""
			(at 0 0 0)
			(layer "B.Fab")
			(effects
				(font
					(size 1.27 1.27)
				)
				(justify mirror)
			)
		)
		(duplicate_pad_numbers_are_jumpers no)
		(fp_line
			(start -0.7874 -0.4064)
			(end -0.7874 0.4064)
			(stroke
				(width 0.1524)
				(type default)
			)
			(layer "B.SilkS")
		)
		(fp_line
			(start -0.7874 0.4064)
			(end 0.7874 0.4064)
			(stroke
				(width 0.1524)
				(type default)
			)
			(layer "B.SilkS")
		)
		(fp_line
			(start 0.7874 -0.4064)
			(end -0.7874 -0.4064)
			(stroke
				(width 0.1524)
				(type default)
			)
			(layer "B.SilkS")
		)
		(fp_line
			(start 0.7874 0.4064)
			(end 0.7874 -0.4064)
			(stroke
				(width 0.1524)
				(type default)
			)
			(layer "B.SilkS")
		)
		(fp_line
			(start -0.67945 -0.3048)
			(end -0.67945 0.3048)
			(stroke
				(width 0.1)
				(type default)
			)
			(layer "B.Fab")
		)
		(fp_line
			(start -0.67945 0.3048)
			(end -0.120396 0.3048)
			(stroke
				(width 0.1)
				(type default)
			)
			(layer "B.Fab")
		)
		(fp_line
			(start -0.12065 -0.3048)
			(end -0.67945 -0.3048)
			(stroke
				(width 0.1)
				(type default)
			)
			(layer "B.Fab")
		)
		(fp_line
			(start -0.12065 -0.2794)
			(end -0.12065 -0.3048)
			(stroke
				(width 0.1)
				(type default)
			)
			(layer "B.Fab")
		)
		(fp_line
			(start -0.120396 0.2794)
			(end 0.12065 0.2794)
			(stroke
				(width 0.1)
				(type default)
			)
			(layer "B.Fab")
		)
		(fp_line
			(start -0.120396 0.3048)
			(end -0.120396 0.2794)
			(stroke
				(width 0.1)
				(type default)
			)
			(layer "B.Fab")
		)
		(fp_line
			(start 0.12065 -0.305054)
			(end 0.12065 -0.2794)
			(stroke
				(width 0.1)
				(type default)
			)
			(layer "B.Fab")
		)
		(fp_line
			(start 0.12065 -0.2794)
			(end -0.12065 -0.2794)
			(stroke
				(width 0.1)
				(type default)
			)
			(layer "B.Fab")
		)
		(fp_line
			(start 0.12065 0.2794)
			(end 0.12065 0.3048)
			(stroke
				(width 0.1)
				(type default)
			)
			(layer "B.Fab")
		)
		(fp_line
			(start 0.12065 0.3048)
			(end 0.67945 0.3048)
			(stroke
				(width 0.1)
				(type default)
			)
			(layer "B.Fab")
		)
		(fp_line
			(start 0.67945 -0.305054)
			(end 0.12065 -0.305054)
			(stroke
				(width 0.1)
				(type default)
			)
			(layer "B.Fab")
		)
		(fp_line
			(start 0.67945 0.3048)
			(end 0.67945 -0.305054)
			(stroke
				(width 0.1)
				(type default)
			)
			(layer "B.Fab")
		)
		(pad "1" smd circle
			(at 0.40005 0 180)
			(size 0 0)
			(layers "B.Cu" "B.Mask" "B.Paste")
			(net "P5V_AUX")
		)
		(pad "2" smd circle
			(at -0.40005 0 180)
			(size 0 0)
			(layers "B.Cu" "B.Mask" "B.Paste")
			(net "P5V_AUX_ADC")
		)
	)
	(footprint ""
		(layer "B.Cu")
		(at 317.918338 -396.393162 -90)
		(property "Reference" "C583"
			(at 0 0 90)
			(layer "B.SilkS")
			(hide yes)
			(effects
				(font
					(size 1.27 1.27)
				)
				(justify mirror)
			)
		)
		(property "Value" ""
			(at 0 0 90)
			(layer "B.Fab")
			(effects
				(font
					(size 1.27 1.27)
				)
				(justify mirror)
			)
		)
		(duplicate_pad_numbers_are_jumpers no)
		(fp_line
			(start -0.299974 0.150114)
			(end 0.299974 0.150114)
			(stroke
				(width 0.1)
				(type default)
			)
			(layer "B.Fab")
		)
		(fp_line
			(start 0.299974 0.150114)
			(end 0.299974 -0.150114)
			(stroke
				(width 0.1)
				(type default)
			)
			(layer "B.Fab")
		)
		(fp_line
			(start -0.299974 -0.150114)
			(end -0.299974 0.150114)
			(stroke
				(width 0.1)
				(type default)
			)
			(layer "B.Fab")
		)
		(fp_line
			(start 0.299974 -0.150114)
			(end -0.299974 -0.150114)
			(stroke
				(width 0.1)
				(type default)
			)
			(layer "B.Fab")
		)
		(pad "1" smd rect
			(at 0.2667 0 90)
			(size 0.3048 0.381)
			(layers "B.Cu" "B.Mask" "B.Paste")
			(net "P0V9_CPU0_RT0_2A")
		)
		(pad "2" smd rect
			(at -0.2667 0 90)
			(size 0.3048 0.381)
			(layers "B.Cu" "B.Mask" "B.Paste")
			(net "GND")
		)
	)
	(footprint ""
		(layer "B.Cu")
		(at 356.29596 -257.744976 180)
		(property "Reference" "C2517"
			(at 0 0 0)
			(layer "B.SilkS")
			(hide yes)
			(effects
				(font
					(size 1.27 1.27)
				)
				(justify mirror)
			)
		)
		(property "Value" ""
			(at 0 0 0)
			(layer "B.Fab")
			(effects
				(font
					(size 1.27 1.27)
				)
				(justify mirror)
			)
		)
		(duplicate_pad_numbers_are_jumpers no)
		(fp_line
			(start 0.7874 0.4064)
			(end 0.7874 -0.4064)
			(stroke
				(width 0.1524)
				(type default)
			)
			(layer "B.SilkS")
		)
		(fp_line
			(start 0.7874 -0.4064)
			(end -0.7874 -0.4064)
			(stroke
				(width 0.1524)
				(type default)
			)
			(layer "B.SilkS")
		)
		(fp_line
			(start -0.7874 0.4064)
			(end 0.7874 0.4064)
			(stroke
				(width 0.1524)
				(type default)
			)
			(layer "B.SilkS")
		)
		(fp_line
			(start -0.7874 -0.4064)
			(end -0.7874 0.4064)
			(stroke
				(width 0.1524)
				(type default)
			)
			(layer "B.SilkS")
		)
		(fp_line
			(start 0.67945 0.3048)
			(end 0.67945 -0.305054)
			(stroke
				(width 0.1)
				(type default)
			)
			(layer "B.Fab")
		)
		(fp_line
			(start 0.67945 -0.305054)
			(end 0.12065 -0.305054)
			(stroke
				(width 0.1)
				(type default)
			)
			(layer "B.Fab")
		)
		(fp_line
			(start 0.12065 0.3048)
			(end 0.67945 0.3048)
			(stroke
				(width 0.1)
				(type default)
			)
			(layer "B.Fab")
		)
		(fp_line
			(start 0.12065 0.2794)
			(end 0.12065 0.3048)
			(stroke
				(width 0.1)
				(type default)
			)
			(layer "B.Fab")
		)
		(fp_line
			(start 0.12065 -0.2794)
			(end -0.12065 -0.2794)
			(stroke
				(width 0.1)
				(type default)
			)
			(layer "B.Fab")
		)
		(fp_line
			(start 0.12065 -0.305054)
			(end 0.12065 -0.2794)
			(stroke
				(width 0.1)
				(type default)
			)
			(layer "B.Fab")
		)
		(fp_line
			(start -0.120396 0.3048)
			(end -0.120396 0.2794)
			(stroke
				(width 0.1)
				(type default)
			)
			(layer "B.Fab")
		)
		(fp_line
			(start -0.120396 0.2794)
			(end 0.12065 0.2794)
			(stroke
				(width 0.1)
				(type default)
			)
			(layer "B.Fab")
		)
		(fp_line
			(start -0.12065 -0.2794)
			(end -0.12065 -0.3048)
			(stroke
				(width 0.1)
				(type default)
			)
			(layer "B.Fab")
		)
		(fp_line
			(start -0.12065 -0.3048)
			(end -0.67945 -0.3048)
			(stroke
				(width 0.1)
				(type default)
			)
			(layer "B.Fab")
		)
		(fp_line
			(start -0.67945 0.3048)
			(end -0.120396 0.3048)
			(stroke
				(width 0.1)
				(type default)
			)
			(layer "B.Fab")
		)
		(fp_line
			(start -0.67945 -0.3048)
			(end -0.67945 0.3048)
			(stroke
				(width 0.1)
				(type default)
			)
			(layer "B.Fab")
		)
		(pad "1" smd circle
			(at 0.40005 0)
			(size 0 0)
			(layers "B.Cu" "B.Mask" "B.Paste")
			(net "PVDD18_S5_P0")
		)
		(pad "2" smd circle
			(at -0.40005 0)
			(size 0 0)
			(layers "B.Cu" "B.Mask" "B.Paste")
			(net "GND")
		)
	)
)
